# S9S_MB_2U (Grand Teton) — schematic netlist excerpt (pin names and nets, part order shuffled) for the footprints in the layout excerpt that follows; sources: Cadence DE-HDL packaged netlist, KiCad conversion of 03242023_DA0F0TMBIJ0_F0T_Motherboard_J_brd_V01_OCP.brd

PC1292  Q_CAP  470PF 50V 10% X7R  pkg 0402  page 292 : A = PVCCFA_EHV_CPU1_BTSEN ; B = GND
C69  Q_CAP  10UF 16V 10% X6S  pkg C0805  page 104 : A = P12V_S3_AUX_CPU1_NVDIMM ; B = GND
C363  Q_CAP  47UF 4V 20% X6S  pkg C0805  page 75 : A = PVCCIN_CPU0 ; B = GND

(kicad_pcb
	(version 20260206)
	(generator "pcbnew")
	(generator_version "10.0")
	(general
		(thickness 1.6)
		(legacy_teardrops no)
	)
	(paper "A4")
	(title_block
		(title "03242023_DA0F0TMBIJ0_F0T_Motherboard_J_brd_V01_OCP.brd")
		(comment 1 "Grand Teton / footprints 4252-4254 of 6105")
	)
	(layers
		(0 "F.Cu" signal "TOP")
		(4 "In1.Cu" signal "GND")
		(6 "In2.Cu" signal "IN1")
		(8 "In3.Cu" signal "GND1")
		(10 "In4.Cu" signal "IN2")
		(12 "In5.Cu" signal "GND2")
		(14 "In6.Cu" signal "IN3")
		(16 "In7.Cu" signal "GND3")
		(18 "In8.Cu" signal "VCC")
		(20 "In9.Cu" signal "VCC1")
		(22 "In10.Cu" signal "GND4")
		(24 "In11.Cu" signal "IN4")
		(26 "In12.Cu" signal "GND5")
		(28 "In13.Cu" signal "IN5")
		(30 "In14.Cu" signal "GND6")
		(32 "In15.Cu" signal "IN6")
		(34 "In16.Cu" signal "GND7")
		(2 "B.Cu" signal "BOTTOM")
		(9 "F.Adhes" user "F.Adhesive")
		(11 "B.Adhes" user "B.Adhesive")
		(13 "F.Paste" user "Package Geometry/Pastemask Top")
		(15 "B.Paste" user "Package Geometry/Pastemask Bottom")
		(5 "F.SilkS" user "Ref Des/Silkscreen Top")
		(7 "B.SilkS" user "Ref Des/Silkscreen Bottom")
		(1 "F.Mask" user "Board Geometry/Soldermask Top")
		(3 "B.Mask" user "Board Geometry/Soldermask Bottom")
		(17 "Dwgs.User" user "User.Drawings")
		(19 "Cmts.User" user "User.Comments")
		(21 "Eco1.User" user "User.Eco1")
		(23 "Eco2.User" user "User.Eco2")
		(25 "Edge.Cuts" user "Board Geometry/Outline")
		(27 "Margin" user)
		(31 "F.CrtYd" user "Package Geometry/Place Bound Top")
		(29 "B.CrtYd" user "Package Geometry/Place Bound Bottom")
		(35 "F.Fab" user "Ref Des/Assembly Top")
		(33 "B.Fab" user "Ref Des/Assembly Bottom")
	)
	(footprint ""
		(layer "B.Cu")
		(at 30.163516 -130.297682 180)
		(property "Reference" "PC1292"
			(at 0 0 0)
			(layer "B.SilkS")
			(hide yes)
			(effects
				(font
					(size 1.27 1.27)
				)
				(justify mirror)
			)
		)
		(property "Value" ""
			(at 0 0 0)
			(layer "B.Fab")
			(effects
				(font
					(size 1.27 1.27)
				)
				(justify mirror)
			)
		)
		(duplicate_pad_numbers_are_jumpers no)
		(fp_line
			(start 0.7874 0.4064)
			(end 0.7874 -0.4064)
			(stroke
				(width 0.1524)
				(type default)
			)
			(layer "B.SilkS")
		)
		(fp_line
			(start 0.7874 -0.4064)
			(end -0.7874 -0.4064)
			(stroke
				(width 0.1524)
				(type default)
			)
			(layer "B.SilkS")
		)
		(fp_line
			(start -0.7874 0.4064)
			(end 0.7874 0.4064)
			(stroke
				(width 0.1524)
				(type default)
			)
			(layer "B.SilkS")
		)
		(fp_line
			(start -0.7874 -0.4064)
			(end -0.7874 0.4064)
			(stroke
				(width 0.1524)
				(type default)
			)
			(layer "B.SilkS")
		)
		(fp_line
			(start 0.67945 0.3048)
			(end 0.67945 -0.305054)
			(stroke
				(width 0.1)
				(type default)
			)
			(layer "B.Fab")
		)
		(fp_line
			(start 0.67945 -0.305054)
			(end 0.12065 -0.305054)
			(stroke
				(width 0.1)
				(type default)
			)
			(layer "B.Fab")
		)
		(fp_line
			(start 0.12065 0.3048)
			(end 0.67945 0.3048)
			(stroke
				(width 0.1)
				(type default)
			)
			(layer "B.Fab")
		)
		(fp_line
			(start 0.12065 0.2794)
			(end 0.12065 0.3048)
			(stroke
				(width 0.1)
				(type default)
			)
			(layer "B.Fab")
		)
		(fp_line
			(start 0.12065 -0.2794)
			(end -0.12065 -0.2794)
			(stroke
				(width 0.1)
				(type default)
			)
			(layer "B.Fab")
		)
		(fp_line
			(start 0.12065 -0.305054)
			(end 0.12065 -0.2794)
			(stroke
				(width 0.1)
				(type default)
			)
			(layer "B.Fab")
		)
		(fp_line
			(start -0.120396 0.3048)
			(end -0.120396 0.2794)
			(stroke
				(width 0.1)
				(type default)
			)
			(layer "B.Fab")
		)
		(fp_line
			(start -0.120396 0.2794)
			(end 0.12065 0.2794)
			(stroke
				(width 0.1)
				(type default)
			)
			(layer "B.Fab")
		)
		(fp_line
			(start -0.12065 -0.2794)
			(end -0.12065 -0.3048)
			(stroke
				(width 0.1)
				(type default)
			)
			(layer "B.Fab")
		)
		(fp_line
			(start -0.12065 -0.3048)
			(end -0.67945 -0.3048)
			(stroke
				(width 0.1)
				(type default)
			)
			(layer "B.Fab")
		)
		(fp_line
			(start -0.67945 0.3048)
			(end -0.120396 0.3048)
			(stroke
				(width 0.1)
				(type default)
			)
			(layer "B.Fab")
		)
		(fp_line
			(start -0.67945 -0.3048)
			(end -0.67945 0.3048)
			(stroke
				(width 0.1)
				(type default)
			)
			(layer "B.Fab")
		)
		(pad "1" smd circle
			(at 0.40005 0)
			(size 0 0)
			(layers "B.Cu" "B.Mask" "B.Paste")
			(net "PVCCFA_EHV_CPU1_BTSEN")
		)
		(pad "2" smd circle
			(at -0.40005 0)
			(size 0 0)
			(layers "B.Cu" "B.Mask" "B.Paste")
			(net "GND")
		)
	)
	(footprint ""
		(layer "B.Cu")
		(at 12.217146 -321.554856 -90)
		(property "Reference" "C69"
			(at 0 0 90)
			(layer "B.SilkS")
			(hide yes)
			(effects
				(font
					(size 1.27 1.27)
				)
				(justify mirror)
			)
		)
		(property "Value" ""
			(at 0 0 90)
			(layer "B.Fab")
			(effects
				(font
					(size 1.27 1.27)
				)
				(justify mirror)
			)
		)
		(duplicate_pad_numbers_are_jumpers no)
		(fp_line
			(start -1.524 0.762)
			(end 1.524 0.762)
			(stroke
				(width 0.1524)
				(type default)
			)
			(layer "B.SilkS")
		)
		(fp_line
			(start 1.524 0.762)
			(end 1.524 -0.762)
			(stroke
				(width 0.1524)
				(type default)
			)
			(layer "B.SilkS")
		)
		(fp_line
			(start -1.524 -0.762)
			(end -1.524 0.762)
			(stroke
				(width 0.1524)
				(type default)
			)
			(layer "B.SilkS")
		)
		(fp_line
			(start 1.524 -0.762)
			(end -1.524 -0.762)
			(stroke
				(width 0.1524)
				(type default)
			)
			(layer "B.SilkS")
		)
		(fp_line
			(start -1.1049 0.724916)
			(end -1.1049 -0.724916)
			(stroke
				(width 0.1)
				(type default)
			)
			(layer "B.Fab")
		)
		(fp_line
			(start 1.1049 0.724916)
			(end -1.1049 0.724916)
			(stroke
				(width 0.1)
				(type default)
			)
			(layer "B.Fab")
		)
		(fp_line
			(start -1.1049 -0.724916)
			(end 1.1049 -0.724916)
			(stroke
				(width 0.1)
				(type default)
			)
			(layer "B.Fab")
		)
		(fp_line
			(start 1.1049 -0.724916)
			(end 1.1049 0.724916)
			(stroke
				(width 0.1)
				(type default)
			)
			(layer "B.Fab")
		)
		(pad "1" smd rect
			(at 0.889 0 270)
			(size 1.016 1.27)
			(layers "B.Cu" "B.Mask" "B.Paste")
			(net "P12V_S3_AUX_CPU1_NVDIMM")
		)
		(pad "2" smd rect
			(at -0.889 0 270)
			(size 1.016 1.27)
			(layers "B.Cu" "B.Mask" "B.Paste")
			(net "GND")
		)
	)
	(footprint ""
		(layer "B.Cu")
		(at 364.342934 -237.717838 90)
		(property "Reference" "C363"
			(at 0 0 90)
			(layer "B.SilkS")
			(hide yes)
			(effects
				(font
					(size 1.27 1.27)
				)
				(justify mirror)
			)
		)
		(property "Value" ""
			(at 0 0 90)
			(layer "B.Fab")
			(effects
				(font
					(size 1.27 1.27)
				)
				(justify mirror)
			)
		)
		(duplicate_pad_numbers_are_jumpers no)
		(fp_line
			(start 1.524 -0.762)
			(end -1.524 -0.762)
			(stroke
				(width 0.1524)
				(type default)
			)
			(layer "B.SilkS")
		)
		(fp_line
			(start -1.524 -0.762)
			(end -1.524 0.762)
			(stroke
				(width 0.1524)
				(type default)
			)
			(layer "B.SilkS")
		)
		(fp_line
			(start 1.524 0.762)
			(end 1.524 -0.762)
			(stroke
				(width 0.1524)
				(type default)
			)
			(layer "B.SilkS")
		)
		(fp_line
			(start -1.524 0.762)
			(end 1.524 0.762)
			(stroke
				(width 0.1524)
				(type default)
			)
			(layer "B.SilkS")
		)
		(fp_line
			(start 1.1049 -0.724916)
			(end 1.1049 0.724916)
			(stroke
				(width 0.1)
				(type default)
			)
			(layer "B.Fab")
		)
		(fp_line
			(start -1.1049 -0.724916)
			(end 1.1049 -0.724916)
			(stroke
				(width 0.1)
				(type default)
			)
			(layer "B.Fab")
		)
		(fp_line
			(start 1.1049 0.724916)
			(end -1.1049 0.724916)
			(stroke
				(width 0.1)
				(type default)
			)
			(layer "B.Fab")
		)
		(fp_line
			(start -1.1049 0.724916)
			(end -1.1049 -0.724916)
			(stroke
				(width 0.1)
				(type default)
			)
			(layer "B.Fab")
		)
		(pad "1" smd rect
			(at 0.889 0 90)
			(size 1.016 1.27)
			(layers "B.Cu" "B.Mask" "B.Paste")
			(net "PVCCIN_CPU0")
		)
		(pad "2" smd rect
			(at -0.889 0 90)
			(size 1.016 1.27)
			(layers "B.Cu" "B.Mask" "B.Paste")
			(net "GND")
		)
	)
)
